# T6G (Grand Teton) — schematic netlist excerpt (pin names and nets, part order shuffled) for the footprints in the layout excerpt that follows; sources: Cadence DE-HDL packaged netlist, KiCad conversion of 04192023_DAF0TMB3IC0_F0TG_MB_C_brd_V02_OCP.brd

U6000  DS125BR111RTWR  IC  pkg WQFN24_TH_0-5_4X4XA  page 112
  \eqb0||ad3\  = FM_P2E_BUF2_EQB0
  \eqb1||ad2\  = FM_P2E_BUF2_EQB1
  ENSMB  = PD_P2E_BUF2_ENSMB
  \sda||voda_db\  = FM_P2E_BUF2_VODA_DB
  \scl||vodb_db\  = FM_P2E_BUF2_VODB_DB
  PWDN  = FM_P2E_EN2_N
  \outa+\  = P2E_MB_BMC_TX_BUF2_DP<0>
  \outa-\  = P2E_MB_BMC_TX_BUF2_DN<0>
  \eqa1||ad1\  = FM_P2E_BUF2_EQA1
  \eqa0||ad0\  = FM_P2E_BUF2_EQA0
  \inb+\  = P2E_MB_BMC_RX_R2_DP<0>
  \inb-\  = P2E_MB_BMC_RX_R2_DN<0>
  RES  = NC_RES
  SD_TH  = FM_P2E_BUF2_SD_TH
  VIN  = P3V3_AUX
  VDD_SEL  = GND
  \vod_sel||readen#\  = FM_P2E_BUF2_VOD_SEL
  \rxdet||done#\  = FM_P2E_BUF2_RXDET
  \outb-\  = P2E_MB_BMC_RX_BUF2_C_DN<0>
  \outb+\  = P2E_MB_BMC_RX_BUF2_C_DP<0>
  VDD_21  = BUF2_VDD
  VDD_22  = BUF2_VDD
  \ina-\  = P2E_MB_BMC_TX_C_R2_DN<0>
  \ina+\  = P2E_MB_BMC_TX_C_R2_DP<0>
  TH_GND  = GND

(kicad_pcb
	(version 20260206)
	(generator "pcbnew")
	(generator_version "10.0")
	(general
		(thickness 1.6)
		(legacy_teardrops no)
	)
	(paper "A4")
	(title_block
		(title "04192023_DAF0TMB3IC0_F0TG_MB_C_brd_V02_OCP.brd")
		(comment 1 "Grand Teton / footprints 2909-2909 of 8354")
	)
	(layers
		(0 "F.Cu" signal "TOP")
		(4 "In1.Cu" signal "GND")
		(6 "In2.Cu" signal "IN1")
		(8 "In3.Cu" signal "GND1")
		(10 "In4.Cu" signal "IN2")
		(12 "In5.Cu" signal "GND2")
		(14 "In6.Cu" signal "IN3")
		(16 "In7.Cu" signal "GND3")
		(18 "In8.Cu" signal "VCC")
		(20 "In9.Cu" signal "VCC1")
		(22 "In10.Cu" signal "GND4")
		(24 "In11.Cu" signal "IN4")
		(26 "In12.Cu" signal "GND5")
		(28 "In13.Cu" signal "IN5")
		(30 "In14.Cu" signal "GND6")
		(32 "In15.Cu" signal "IN6")
		(34 "In16.Cu" signal "GND7")
		(2 "B.Cu" signal "BOTTOM")
		(9 "F.Adhes" user "F.Adhesive")
		(11 "B.Adhes" user "B.Adhesive")
		(13 "F.Paste" user "Package Geometry/Pastemask Top")
		(15 "B.Paste" user "Package Geometry/Pastemask Bottom")
		(5 "F.SilkS" user "Ref Des/Silkscreen Top")
		(7 "B.SilkS" user "Ref Des/Silkscreen Bottom")
		(1 "F.Mask" user "Board Geometry/Soldermask Top")
		(3 "B.Mask" user "Board Geometry/Soldermask Bottom")
		(17 "Dwgs.User" user "User.Drawings")
		(19 "Cmts.User" user "User.Comments")
		(21 "Eco1.User" user "User.Eco1")
		(23 "Eco2.User" user "User.Eco2")
		(25 "Edge.Cuts" user "Board Geometry/Outline")
		(27 "Margin" user)
		(31 "F.CrtYd" user "Package Geometry/Place Bound Top")
		(29 "B.CrtYd" user "Package Geometry/Place Bound Bottom")
		(35 "F.Fab" user "Ref Des/Assembly Top")
		(33 "B.Fab" user "Ref Des/Assembly Bottom")
	)
	(footprint ""
		(layer "F.Cu")
		(at 16.623284 -423.13352 -90)
		(property "Reference" "U6000"
			(at -5.784342 3.991102 0)
			(unlocked yes)
			(layer "F.SilkS")
			(effects
				(font
					(size 0.7874 0.5842)
					(thickness 0.1524)
				)
				(justify left)
			)
		)
		(property "Value" ""
			(at 0 0 270)
			(layer "F.Fab")
			(effects
				(font
					(size 1.27 1.27)
				)
			)
		)
		(duplicate_pad_numbers_are_jumpers no)
		(fp_line
			(start -2.050034 2.050034)
			(end -2.050034 1.524)
			(stroke
				(width 0.1524)
				(type default)
			)
			(layer "F.SilkS")
		)
		(fp_line
			(start -1.524 2.050034)
			(end -2.050034 2.050034)
			(stroke
				(width 0.1524)
				(type default)
			)
			(layer "F.SilkS")
		)
		(fp_line
			(start 2.050034 2.050034)
			(end 1.524 2.050034)
			(stroke
				(width 0.1524)
				(type default)
			)
			(layer "F.SilkS")
		)
		(fp_line
			(start 2.050034 1.524)
			(end 2.050034 2.050034)
			(stroke
				(width 0.1524)
				(type default)
			)
			(layer "F.SilkS")
		)
		(fp_line
			(start -2.050034 -1.524)
			(end -2.050034 -2.050034)
			(stroke
				(width 0.1524)
				(type default)
			)
			(layer "F.SilkS")
		)
		(fp_line
			(start -2.050034 -2.050034)
			(end -1.524 -2.050034)
			(stroke
				(width 0.1524)
				(type default)
			)
			(layer "F.SilkS")
		)
		(fp_line
			(start 1.524 -2.050034)
			(end 2.050034 -2.050034)
			(stroke
				(width 0.1524)
				(type default)
			)
			(layer "F.SilkS")
		)
		(fp_line
			(start 2.050034 -2.050034)
			(end 2.050034 -1.524)
			(stroke
				(width 0.1524)
				(type default)
			)
			(layer "F.SilkS")
		)
		(fp_rect
			(start -2.050034 -2.126234)
			(end -2.634234 -1.542034)
			(stroke
				(width 0)
				(type default)
			)
			(fill yes)
			(layer "F.SilkS")
		)
		(fp_line
			(start -2.050034 2.050034)
			(end -2.050034 -2.050034)
			(stroke
				(width 0.1)
				(type default)
			)
			(layer "F.Fab")
		)
		(fp_line
			(start 2.050034 2.050034)
			(end -2.050034 2.050034)
			(stroke
				(width 0.1)
				(type default)
			)
			(layer "F.Fab")
		)
		(fp_line
			(start -2.050034 -2.050034)
			(end 2.050034 -2.050034)
			(stroke
				(width 0.1)
				(type default)
			)
			(layer "F.Fab")
		)
		(fp_line
			(start 2.050034 -2.050034)
			(end 2.050034 2.050034)
			(stroke
				(width 0.1)
				(type default)
			)
			(layer "F.Fab")
		)
		(fp_poly
			(pts
				(xy -2.634234 -1.542034) (xy -2.050034 -1.542034) (xy -2.050034 -2.126234) (xy -2.634234 -2.126234)
			)
			(stroke
				(width 0)
				(type default)
			)
			(fill yes)
			(layer "F.Fab")
		)
		(pad "1" smd circle
			(at -1.89992 -1.249934 180)
			(size 0 0)
			(layers "F.Cu" "F.Mask" "F.Paste")
			(net "FM_P2E_BUF2_EQB0")
		)
		(pad "2" smd circle
			(at -1.89992 -0.750062 180)
			(size 0 0)
			(layers "F.Cu" "F.Mask" "F.Paste")
			(net "FM_P2E_BUF2_EQB1")
		)
		(pad "3" smd circle
			(at -1.89992 -0.249936 180)
			(size 0 0)
			(layers "F.Cu" "F.Mask" "F.Paste")
			(net "PD_P2E_BUF2_ENSMB")
		)
		(pad "4" smd circle
			(at -1.89992 0.249936 180)
			(size 0 0)
			(layers "F.Cu" "F.Mask" "F.Paste")
			(net "FM_P2E_BUF2_VODA_DB")
		)
		(pad "5" smd circle
			(at -1.89992 0.750062 180)
			(size 0 0)
			(layers "F.Cu" "F.Mask" "F.Paste")
			(net "FM_P2E_BUF2_VODB_DB")
		)
		(pad "6" smd circle
			(at -1.89992 1.249934 180)
			(size 0 0)
			(layers "F.Cu" "F.Mask" "F.Paste")
			(net "FM_P2E_EN2_N")
		)
		(pad "7" smd circle
			(at -1.249934 1.89992 270)
			(size 0 0)
			(layers "F.Cu" "F.Mask" "F.Paste")
			(net "P2E_MB_BMC_TX_BUF2_DP<0>")
		)
		(pad "8" smd circle
			(at -0.750062 1.89992 270)
			(size 0 0)
			(layers "F.Cu" "F.Mask" "F.Paste")
			(net "P2E_MB_BMC_TX_BUF2_DN<0>")
		)
		(pad "9" smd circle
			(at -0.249936 1.89992 270)
			(size 0 0)
			(layers "F.Cu" "F.Mask" "F.Paste")
			(net "FM_P2E_BUF2_EQA1")
		)
		(pad "10" smd circle
			(at 0.249936 1.89992 270)
			(size 0 0)
			(layers "F.Cu" "F.Mask" "F.Paste")
			(net "FM_P2E_BUF2_EQA0")
		)
		(pad "11" smd circle
			(at 0.750062 1.89992 270)
			(size 0 0)
			(layers "F.Cu" "F.Mask" "F.Paste")
			(net "P2E_MB_BMC_RX_R2_DP<0>")
		)
		(pad "12" smd circle
			(at 1.249934 1.89992 270)
			(size 0 0)
			(layers "F.Cu" "F.Mask" "F.Paste")
			(net "P2E_MB_BMC_RX_R2_DN<0>")
		)
		(pad "13" smd circle
			(at 1.89992 1.249934 180)
			(size 0 0)
			(layers "F.Cu" "F.Mask" "F.Paste")
			(net "NC_RES")
		)
		(pad "14" smd circle
			(at 1.89992 0.750062 180)
			(size 0 0)
			(layers "F.Cu" "F.Mask" "F.Paste")
			(net "FM_P2E_BUF2_SD_TH")
		)
		(pad "15" smd circle
			(at 1.89992 0.249936 180)
			(size 0 0)
			(layers "F.Cu" "F.Mask" "F.Paste")
			(net "P3V3_AUX")
		)
		(pad "16" smd circle
			(at 1.89992 -0.249936 180)
			(size 0 0)
			(layers "F.Cu" "F.Mask" "F.Paste")
			(net "GND")
		)
		(pad "17" smd circle
			(at 1.89992 -0.750062 180)
			(size 0 0)
			(layers "F.Cu" "F.Mask" "F.Paste")
			(net "FM_P2E_BUF2_VOD_SEL")
		)
		(pad "18" smd circle
			(at 1.89992 -1.249934 180)
			(size 0 0)
			(layers "F.Cu" "F.Mask" "F.Paste")
			(net "FM_P2E_BUF2_RXDET")
		)
		(pad "19" smd circle
			(at 1.249934 -1.89992 270)
			(size 0 0)
			(layers "F.Cu" "F.Mask" "F.Paste")
			(net "P2E_MB_BMC_RX_BUF2_C_DN<0>")
		)
		(pad "20" smd circle
			(at 0.750062 -1.89992 270)
			(size 0 0)
			(layers "F.Cu" "F.Mask" "F.Paste")
			(net "P2E_MB_BMC_RX_BUF2_C_DP<0>")
		)
		(pad "21" smd circle
			(at 0.249936 -1.89992 270)
			(size 0 0)
			(layers "F.Cu" "F.Mask" "F.Paste")
			(net "BUF2_VDD")
		)
		(pad "22" smd circle
			(at -0.249936 -1.89992 270)
			(size 0 0)
			(layers "F.Cu" "F.Mask" "F.Paste")
			(net "BUF2_VDD")
		)
		(pad "23" smd circle
			(at -0.750062 -1.89992 270)
			(size 0 0)
			(layers "F.Cu" "F.Mask" "F.Paste")
			(net "P2E_MB_BMC_TX_C_R2_DN<0>")
		)
		(pad "24" smd circle
			(at -1.249934 -1.89992 270)
			(size 0 0)
			(layers "F.Cu" "F.Mask" "F.Paste")
			(net "P2E_MB_BMC_TX_C_R2_DP<0>")
		)
		(pad "25" smd circle
			(at 0 0 270)
			(size 0 0)
			(layers "F.Cu" "F.Mask" "F.Paste")
			(net "GND")
		)
		(zone
			(layer "F.Cu")
			(hatch none 0.5)
			(connect_pads
				(clearance 0)
			)
			(min_thickness 0.25)
			(keepout
				(tracks not_allowed)
				(vias allowed)
				(pads allowed)
				(copperpour not_allowed)
				(footprints allowed)
			)
			(placement
				(enabled no)
				(sheetname "")
			)
			(fill
				(thermal_gap 0.5)
				(thermal_bridge_width 0.5)
				(island_removal_mode 0)
			)
			(polygon
				(pts
					(xy 16.597884 -424.65752) (xy 16.597884 -424.50512) (xy 15.251684 -424.50512) (xy 15.251684 -421.76192)
					(xy 16.732758 -421.76192) (xy 16.732758 -421.60952) (xy 15.099284 -421.60952) (xy 15.099284 -424.65752)
				)
			)
		)
	)
)
